(kicad_pcb
	(version 20260206)
	(generator "pcbnew")
	(generator_version "10.0")
	(general
		(thickness 1.6)
		(legacy_teardrops no)
	)
	(paper "A4")
	(title_block
		(title "01162023_DA0F0TEBIF0_F0T_Expander_BD_F_brd_V02_OCP.brd")
		(comment 1 "Grand Teton / footprints 797-803 of 9728")
	)
	(layers
		(0 "F.Cu" signal "TOP")
		(4 "In1.Cu" signal "GND")
		(6 "In2.Cu" signal "VCC")
		(8 "In3.Cu" signal "VCC1")
		(10 "In4.Cu" signal "GND1")
		(12 "In5.Cu" signal "IN1")
		(14 "In6.Cu" signal "GND2")
		(16 "In7.Cu" signal "IN2")
		(18 "In8.Cu" signal "GND3")
		(20 "In9.Cu" signal "IN3")
		(22 "In10.Cu" signal "GND4")
		(24 "In11.Cu" signal "IN4")
		(26 "In12.Cu" signal "GND5")
		(28 "In13.Cu" signal "IN5")
		(30 "In14.Cu" signal "GND6")
		(32 "In15.Cu" signal "IN6")
		(34 "In16.Cu" signal "GND7")
		(2 "B.Cu" signal "BOTTOM")
		(9 "F.Adhes" user "F.Adhesive")
		(11 "B.Adhes" user "B.Adhesive")
		(13 "F.Paste" user "Package Geometry/Pastemask Top")
		(15 "B.Paste" user "Package Geometry/Pastemask Bottom")
		(5 "F.SilkS" user "Ref Des/Silkscreen Top")
		(7 "B.SilkS" user "Ref Des/Silkscreen Bottom")
		(1 "F.Mask" user "Board Geometry/Soldermask Top")
		(3 "B.Mask" user "Board Geometry/Soldermask Bottom")
		(17 "Dwgs.User" user "User.Drawings")
		(19 "Cmts.User" user "User.Comments")
		(21 "Eco1.User" user "User.Eco1")
		(23 "Eco2.User" user "User.Eco2")
		(25 "Edge.Cuts" user "Board Geometry/Outline")
		(27 "Margin" user)
		(31 "F.CrtYd" user "Package Geometry/Place Bound Top")
		(29 "B.CrtYd" user "Package Geometry/Place Bound Bottom")
		(35 "F.Fab" user "Ref Des/Assembly Top")
		(33 "B.Fab" user "Ref Des/Assembly Bottom")
	)
	(footprint ""
		(layer "F.Cu")
		(at 427.762416 -22.937216 90)
		(property "Reference" "R1739"
			(at 0 0 90)
			(layer "F.SilkS")
			(hide yes)
			(effects
				(font
					(size 1.27 1.27)
				)
			)
		)
		(property "Value" ""
			(at 0 0 90)
			(layer "F.Fab")
			(effects
				(font
					(size 1.27 1.27)
				)
			)
		)
		(duplicate_pad_numbers_are_jumpers no)
		(fp_line
			(start 0.7874 -0.4064)
			(end 0.7874 0.4064)
			(stroke
				(width 0.1524)
				(type default)
			)
			(layer "F.SilkS")
		)
		(fp_line
			(start -0.7874 -0.4064)
			(end 0.7874 -0.4064)
			(stroke
				(width 0.1524)
				(type default)
			)
			(layer "F.SilkS")
		)
		(fp_line
			(start 0.7874 0.4064)
			(end -0.7874 0.4064)
			(stroke
				(width 0.1524)
				(type default)
			)
			(layer "F.SilkS")
		)
		(fp_line
			(start -0.7874 0.4064)
			(end -0.7874 -0.4064)
			(stroke
				(width 0.1524)
				(type default)
			)
			(layer "F.SilkS")
		)
		(fp_line
			(start -0.12065 -0.305054)
			(end -0.12065 -0.2794)
			(stroke
				(width 0.1)
				(type default)
			)
			(layer "F.Fab")
		)
		(fp_line
			(start -0.67945 -0.305054)
			(end -0.12065 -0.305054)
			(stroke
				(width 0.1)
				(type default)
			)
			(layer "F.Fab")
		)
		(fp_line
			(start 0.67945 -0.3048)
			(end 0.67945 0.3048)
			(stroke
				(width 0.1)
				(type default)
			)
			(layer "F.Fab")
		)
		(fp_line
			(start 0.12065 -0.3048)
			(end 0.67945 -0.3048)
			(stroke
				(width 0.1)
				(type default)
			)
			(layer "F.Fab")
		)
		(fp_line
			(start 0.12065 -0.2794)
			(end 0.12065 -0.3048)
			(stroke
				(width 0.1)
				(type default)
			)
			(layer "F.Fab")
		)
		(fp_line
			(start -0.12065 -0.2794)
			(end 0.12065 -0.2794)
			(stroke
				(width 0.1)
				(type default)
			)
			(layer "F.Fab")
		)
		(fp_line
			(start 0.120396 0.2794)
			(end -0.12065 0.2794)
			(stroke
				(width 0.1)
				(type default)
			)
			(layer "F.Fab")
		)
		(fp_line
			(start -0.12065 0.2794)
			(end -0.12065 0.3048)
			(stroke
				(width 0.1)
				(type default)
			)
			(layer "F.Fab")
		)
		(fp_line
			(start 0.67945 0.3048)
			(end 0.120396 0.3048)
			(stroke
				(width 0.1)
				(type default)
			)
			(layer "F.Fab")
		)
		(fp_line
			(start 0.120396 0.3048)
			(end 0.120396 0.2794)
			(stroke
				(width 0.1)
				(type default)
			)
			(layer "F.Fab")
		)
		(fp_line
			(start -0.12065 0.3048)
			(end -0.67945 0.3048)
			(stroke
				(width 0.1)
				(type default)
			)
			(layer "F.Fab")
		)
		(fp_line
			(start -0.67945 0.3048)
			(end -0.67945 -0.305054)
			(stroke
				(width 0.1)
				(type default)
			)
			(layer "F.Fab")
		)
		(pad "1" smd circle
			(at -0.40005 0 90)
			(size 0 0)
			(layers "F.Cu" "F.Mask" "F.Paste")
			(net "SMB_BIC_I2C9_MUX1_SSD14_R_SDA")
		)
		(pad "2" smd circle
			(at 0.40005 0 90)
			(size 0 0)
			(layers "F.Cu" "F.Mask" "F.Paste")
			(net "SMB_ISO_SSD14_SDA")
		)
	)
	(footprint ""
		(layer "F.Cu")
		(at 192.582038 -38.041072 180)
		(property "Reference" "R6073"
			(at 0 0 180)
			(layer "F.SilkS")
			(hide yes)
			(effects
				(font
					(size 1.27 1.27)
				)
			)
		)
		(property "Value" ""
			(at 0 0 180)
			(layer "F.Fab")
			(effects
				(font
					(size 1.27 1.27)
				)
			)
		)
		(duplicate_pad_numbers_are_jumpers no)
		(fp_line
			(start 0.7874 0.4064)
			(end -0.7874 0.4064)
			(stroke
				(width 0.1524)
				(type default)
			)
			(layer "F.SilkS")
		)
		(fp_line
			(start 0.7874 -0.4064)
			(end 0.7874 0.4064)
			(stroke
				(width 0.1524)
				(type default)
			)
			(layer "F.SilkS")
		)
		(fp_line
			(start -0.7874 0.4064)
			(end -0.7874 -0.4064)
			(stroke
				(width 0.1524)
				(type default)
			)
			(layer "F.SilkS")
		)
		(fp_line
			(start -0.7874 -0.4064)
			(end 0.7874 -0.4064)
			(stroke
				(width 0.1524)
				(type default)
			)
			(layer "F.SilkS")
		)
		(fp_line
			(start 0.67945 0.3048)
			(end 0.120396 0.3048)
			(stroke
				(width 0.1)
				(type default)
			)
			(layer "F.Fab")
		)
		(fp_line
			(start 0.67945 -0.3048)
			(end 0.67945 0.3048)
			(stroke
				(width 0.1)
				(type default)
			)
			(layer "F.Fab")
		)
		(fp_line
			(start 0.12065 -0.2794)
			(end 0.12065 -0.3048)
			(stroke
				(width 0.1)
				(type default)
			)
			(layer "F.Fab")
		)
		(fp_line
			(start 0.12065 -0.3048)
			(end 0.67945 -0.3048)
			(stroke
				(width 0.1)
				(type default)
			)
			(layer "F.Fab")
		)
		(fp_line
			(start 0.120396 0.3048)
			(end 0.120396 0.2794)
			(stroke
				(width 0.1)
				(type default)
			)
			(layer "F.Fab")
		)
		(fp_line
			(start 0.120396 0.2794)
			(end -0.12065 0.2794)
			(stroke
				(width 0.1)
				(type default)
			)
			(layer "F.Fab")
		)
		(fp_line
			(start -0.12065 0.3048)
			(end -0.67945 0.3048)
			(stroke
				(width 0.1)
				(type default)
			)
			(layer "F.Fab")
		)
		(fp_line
			(start -0.12065 0.2794)
			(end -0.12065 0.3048)
			(stroke
				(width 0.1)
				(type default)
			)
			(layer "F.Fab")
		)
		(fp_line
			(start -0.12065 -0.2794)
			(end 0.12065 -0.2794)
			(stroke
				(width 0.1)
				(type default)
			)
			(layer "F.Fab")
		)
		(fp_line
			(start -0.12065 -0.305054)
			(end -0.12065 -0.2794)
			(stroke
				(width 0.1)
				(type default)
			)
			(layer "F.Fab")
		)
		(fp_line
			(start -0.67945 0.3048)
			(end -0.67945 -0.305054)
			(stroke
				(width 0.1)
				(type default)
			)
			(layer "F.Fab")
		)
		(fp_line
			(start -0.67945 -0.305054)
			(end -0.12065 -0.305054)
			(stroke
				(width 0.1)
				(type default)
			)
			(layer "F.Fab")
		)
		(pad "1" smd circle
			(at -0.40005 0 180)
			(size 0 0)
			(layers "F.Cu" "F.Mask" "F.Paste")
			(net "P5V_AUX")
		)
		(pad "2" smd circle
			(at 0.40005 0 180)
			(size 0 0)
			(layers "F.Cu" "F.Mask" "F.Paste")
			(net "P3V3_SSD7_PG_G2")
		)
	)
	(footprint ""
		(layer "F.Cu")
		(at 45.257974 -72.766682 90)
		(property "Reference" "PC644"
			(at 0 0 90)
			(layer "F.SilkS")
			(hide yes)
			(effects
				(font
					(size 1.27 1.27)
				)
			)
		)
		(property "Value" ""
			(at 0 0 90)
			(layer "F.Fab")
			(effects
				(font
					(size 1.27 1.27)
				)
			)
		)
		(duplicate_pad_numbers_are_jumpers no)
		(fp_line
			(start 0.7874 -0.4064)
			(end 0.7874 0.4064)
			(stroke
				(width 0.1524)
				(type default)
			)
			(layer "F.SilkS")
		)
		(fp_line
			(start -0.7874 -0.4064)
			(end 0.7874 -0.4064)
			(stroke
				(width 0.1524)
				(type default)
			)
			(layer "F.SilkS")
		)
		(fp_line
			(start 0.7874 0.4064)
			(end -0.7874 0.4064)
			(stroke
				(width 0.1524)
				(type default)
			)
			(layer "F.SilkS")
		)
		(fp_line
			(start -0.7874 0.4064)
			(end -0.7874 -0.4064)
			(stroke
				(width 0.1524)
				(type default)
			)
			(layer "F.SilkS")
		)
		(fp_line
			(start -0.12065 -0.305054)
			(end -0.12065 -0.2794)
			(stroke
				(width 0.1)
				(type default)
			)
			(layer "F.Fab")
		)
		(fp_line
			(start -0.67945 -0.305054)
			(end -0.12065 -0.305054)
			(stroke
				(width 0.1)
				(type default)
			)
			(layer "F.Fab")
		)
		(fp_line
			(start 0.67945 -0.3048)
			(end 0.67945 0.3048)
			(stroke
				(width 0.1)
				(type default)
			)
			(layer "F.Fab")
		)
		(fp_line
			(start 0.12065 -0.3048)
			(end 0.67945 -0.3048)
			(stroke
				(width 0.1)
				(type default)
			)
			(layer "F.Fab")
		)
		(fp_line
			(start 0.12065 -0.2794)
			(end 0.12065 -0.3048)
			(stroke
				(width 0.1)
				(type default)
			)
			(layer "F.Fab")
		)
		(fp_line
			(start -0.12065 -0.2794)
			(end 0.12065 -0.2794)
			(stroke
				(width 0.1)
				(type default)
			)
			(layer "F.Fab")
		)
		(fp_line
			(start 0.120396 0.2794)
			(end -0.12065 0.2794)
			(stroke
				(width 0.1)
				(type default)
			)
			(layer "F.Fab")
		)
		(fp_line
			(start -0.12065 0.2794)
			(end -0.12065 0.3048)
			(stroke
				(width 0.1)
				(type default)
			)
			(layer "F.Fab")
		)
		(fp_line
			(start 0.67945 0.3048)
			(end 0.120396 0.3048)
			(stroke
				(width 0.1)
				(type default)
			)
			(layer "F.Fab")
		)
		(fp_line
			(start 0.120396 0.3048)
			(end 0.120396 0.2794)
			(stroke
				(width 0.1)
				(type default)
			)
			(layer "F.Fab")
		)
		(fp_line
			(start -0.12065 0.3048)
			(end -0.67945 0.3048)
			(stroke
				(width 0.1)
				(type default)
			)
			(layer "F.Fab")
		)
		(fp_line
			(start -0.67945 0.3048)
			(end -0.67945 -0.305054)
			(stroke
				(width 0.1)
				(type default)
			)
			(layer "F.Fab")
		)
		(pad "1" smd circle
			(at -0.40005 0 90)
			(size 0 0)
			(layers "F.Cu" "F.Mask" "F.Paste")
			(net "P12V_SSD1_CO_MODE")
		)
		(pad "2" smd circle
			(at 0.40005 0 90)
			(size 0 0)
			(layers "F.Cu" "F.Mask" "F.Paste")
			(net "GND")
		)
	)
	(footprint ""
		(layer "F.Cu")
		(at 385.304792 -142.88897 180)
		(property "Reference" "R335"
			(at 0 0 180)
			(layer "F.SilkS")
			(hide yes)
			(effects
				(font
					(size 1.27 1.27)
				)
			)
		)
		(property "Value" ""
			(at 0 0 180)
			(layer "F.Fab")
			(effects
				(font
					(size 1.27 1.27)
				)
			)
		)
		(duplicate_pad_numbers_are_jumpers no)
		(fp_line
			(start 0.7874 0.4064)
			(end -0.7874 0.4064)
			(stroke
				(width 0.1524)
				(type default)
			)
			(layer "F.SilkS")
		)
		(fp_line
			(start 0.7874 -0.4064)
			(end 0.7874 0.4064)
			(stroke
				(width 0.1524)
				(type default)
			)
			(layer "F.SilkS")
		)
		(fp_line
			(start -0.7874 0.4064)
			(end -0.7874 -0.4064)
			(stroke
				(width 0.1524)
				(type default)
			)
			(layer "F.SilkS")
		)
		(fp_line
			(start -0.7874 -0.4064)
			(end 0.7874 -0.4064)
			(stroke
				(width 0.1524)
				(type default)
			)
			(layer "F.SilkS")
		)
		(fp_line
			(start 0.67945 0.3048)
			(end 0.120396 0.3048)
			(stroke
				(width 0.1)
				(type default)
			)
			(layer "F.Fab")
		)
		(fp_line
			(start 0.67945 -0.3048)
			(end 0.67945 0.3048)
			(stroke
				(width 0.1)
				(type default)
			)
			(layer "F.Fab")
		)
		(fp_line
			(start 0.12065 -0.2794)
			(end 0.12065 -0.3048)
			(stroke
				(width 0.1)
				(type default)
			)
			(layer "F.Fab")
		)
		(fp_line
			(start 0.12065 -0.3048)
			(end 0.67945 -0.3048)
			(stroke
				(width 0.1)
				(type default)
			)
			(layer "F.Fab")
		)
		(fp_line
			(start 0.120396 0.3048)
			(end 0.120396 0.2794)
			(stroke
				(width 0.1)
				(type default)
			)
			(layer "F.Fab")
		)
		(fp_line
			(start 0.120396 0.2794)
			(end -0.12065 0.2794)
			(stroke
				(width 0.1)
				(type default)
			)
			(layer "F.Fab")
		)
		(fp_line
			(start -0.12065 0.3048)
			(end -0.67945 0.3048)
			(stroke
				(width 0.1)
				(type default)
			)
			(layer "F.Fab")
		)
		(fp_line
			(start -0.12065 0.2794)
			(end -0.12065 0.3048)
			(stroke
				(width 0.1)
				(type default)
			)
			(layer "F.Fab")
		)
		(fp_line
			(start -0.12065 -0.2794)
			(end 0.12065 -0.2794)
			(stroke
				(width 0.1)
				(type default)
			)
			(layer "F.Fab")
		)
		(fp_line
			(start -0.12065 -0.305054)
			(end -0.12065 -0.2794)
			(stroke
				(width 0.1)
				(type default)
			)
			(layer "F.Fab")
		)
		(fp_line
			(start -0.67945 0.3048)
			(end -0.67945 -0.305054)
			(stroke
				(width 0.1)
				(type default)
			)
			(layer "F.Fab")
		)
		(fp_line
			(start -0.67945 -0.305054)
			(end -0.12065 -0.305054)
			(stroke
				(width 0.1)
				(type default)
			)
			(layer "F.Fab")
		)
		(pad "1" smd circle
			(at -0.40005 0 180)
			(size 0 0)
			(layers "F.Cu" "F.Mask" "F.Paste")
			(net "NIC6_BIF0_N")
		)
		(pad "2" smd circle
			(at 0.40005 0 180)
			(size 0 0)
			(layers "F.Cu" "F.Mask" "F.Paste")
			(net "P3V3_AUX")
		)
	)
	(footprint ""
		(layer "F.Cu")
		(at 348.107 -234.061 -90)
		(property "Reference" "R3570"
			(at 0 0 270)
			(layer "F.SilkS")
			(hide yes)
			(effects
				(font
					(size 1.27 1.27)
				)
			)
		)
		(property "Value" ""
			(at 0 0 270)
			(layer "F.Fab")
			(effects
				(font
					(size 1.27 1.27)
				)
			)
		)
		(duplicate_pad_numbers_are_jumpers no)
		(fp_line
			(start -0.7874 0.4064)
			(end -0.7874 -0.4064)
			(stroke
				(width 0.1524)
				(type default)
			)
			(layer "F.SilkS")
		)
		(fp_line
			(start 0.7874 0.4064)
			(end -0.7874 0.4064)
			(stroke
				(width 0.1524)
				(type default)
			)
			(layer "F.SilkS")
		)
		(fp_line
			(start -0.7874 -0.4064)
			(end 0.7874 -0.4064)
			(stroke
				(width 0.1524)
				(type default)
			)
			(layer "F.SilkS")
		)
		(fp_line
			(start 0.7874 -0.4064)
			(end 0.7874 0.4064)
			(stroke
				(width 0.1524)
				(type default)
			)
			(layer "F.SilkS")
		)
		(fp_line
			(start -0.67945 0.3048)
			(end -0.67945 -0.305054)
			(stroke
				(width 0.1)
				(type default)
			)
			(layer "F.Fab")
		)
		(fp_line
			(start -0.12065 0.3048)
			(end -0.67945 0.3048)
			(stroke
				(width 0.1)
				(type default)
			)
			(layer "F.Fab")
		)
		(fp_line
			(start 0.120396 0.3048)
			(end 0.120396 0.2794)
			(stroke
				(width 0.1)
				(type default)
			)
			(layer "F.Fab")
		)
		(fp_line
			(start 0.67945 0.3048)
			(end 0.120396 0.3048)
			(stroke
				(width 0.1)
				(type default)
			)
			(layer "F.Fab")
		)
		(fp_line
			(start -0.12065 0.2794)
			(end -0.12065 0.3048)
			(stroke
				(width 0.1)
				(type default)
			)
			(layer "F.Fab")
		)
		(fp_line
			(start 0.120396 0.2794)
			(end -0.12065 0.2794)
			(stroke
				(width 0.1)
				(type default)
			)
			(layer "F.Fab")
		)
		(fp_line
			(start -0.12065 -0.2794)
			(end 0.12065 -0.2794)
			(stroke
				(width 0.1)
				(type default)
			)
			(layer "F.Fab")
		)
		(fp_line
			(start 0.12065 -0.2794)
			(end 0.12065 -0.3048)
			(stroke
				(width 0.1)
				(type default)
			)
			(layer "F.Fab")
		)
		(fp_line
			(start 0.12065 -0.3048)
			(end 0.67945 -0.3048)
			(stroke
				(width 0.1)
				(type default)
			)
			(layer "F.Fab")
		)
		(fp_line
			(start 0.67945 -0.3048)
			(end 0.67945 0.3048)
			(stroke
				(width 0.1)
				(type default)
			)
			(layer "F.Fab")
		)
		(fp_line
			(start -0.67945 -0.305054)
			(end -0.12065 -0.305054)
			(stroke
				(width 0.1)
				(type default)
			)
			(layer "F.Fab")
		)
		(fp_line
			(start -0.12065 -0.305054)
			(end -0.12065 -0.2794)
			(stroke
				(width 0.1)
				(type default)
			)
			(layer "F.Fab")
		)
		(pad "1" smd circle
			(at -0.40005 0 270)
			(size 0 0)
			(layers "F.Cu" "F.Mask" "F.Paste")
			(net "SSD5_CLK_EN_R_N")
		)
		(pad "2" smd circle
			(at 0.40005 0 270)
			(size 0 0)
			(layers "F.Cu" "F.Mask" "F.Paste")
			(net "SSD5_CLK_EN_N")
		)
	)
	(footprint ""
		(layer "F.Cu")
		(at 365.491776 -152.71115 90)
		(property "Reference" "R757"
			(at 0 0 90)
			(layer "F.SilkS")
			(hide yes)
			(effects
				(font
					(size 1.27 1.27)
				)
			)
		)
		(property "Value" ""
			(at 0 0 90)
			(layer "F.Fab")
			(effects
				(font
					(size 1.27 1.27)
				)
			)
		)
		(duplicate_pad_numbers_are_jumpers no)
		(fp_line
			(start 0.7874 -0.4064)
			(end 0.7874 0.4064)
			(stroke
				(width 0.1524)
				(type default)
			)
			(layer "F.SilkS")
		)
		(fp_line
			(start -0.7874 -0.4064)
			(end 0.7874 -0.4064)
			(stroke
				(width 0.1524)
				(type default)
			)
			(layer "F.SilkS")
		)
		(fp_line
			(start 0.7874 0.4064)
			(end -0.7874 0.4064)
			(stroke
				(width 0.1524)
				(type default)
			)
			(layer "F.SilkS")
		)
		(fp_line
			(start -0.7874 0.4064)
			(end -0.7874 -0.4064)
			(stroke
				(width 0.1524)
				(type default)
			)
			(layer "F.SilkS")
		)
		(fp_line
			(start -0.12065 -0.305054)
			(end -0.12065 -0.2794)
			(stroke
				(width 0.1)
				(type default)
			)
			(layer "F.Fab")
		)
		(fp_line
			(start -0.67945 -0.305054)
			(end -0.12065 -0.305054)
			(stroke
				(width 0.1)
				(type default)
			)
			(layer "F.Fab")
		)
		(fp_line
			(start 0.67945 -0.3048)
			(end 0.67945 0.3048)
			(stroke
				(width 0.1)
				(type default)
			)
			(layer "F.Fab")
		)
		(fp_line
			(start 0.12065 -0.3048)
			(end 0.67945 -0.3048)
			(stroke
				(width 0.1)
				(type default)
			)
			(layer "F.Fab")
		)
		(fp_line
			(start 0.12065 -0.2794)
			(end 0.12065 -0.3048)
			(stroke
				(width 0.1)
				(type default)
			)
			(layer "F.Fab")
		)
		(fp_line
			(start -0.12065 -0.2794)
			(end 0.12065 -0.2794)
			(stroke
				(width 0.1)
				(type default)
			)
			(layer "F.Fab")
		)
		(fp_line
			(start 0.120396 0.2794)
			(end -0.12065 0.2794)
			(stroke
				(width 0.1)
				(type default)
			)
			(layer "F.Fab")
		)
		(fp_line
			(start -0.12065 0.2794)
			(end -0.12065 0.3048)
			(stroke
				(width 0.1)
				(type default)
			)
			(layer "F.Fab")
		)
		(fp_line
			(start 0.67945 0.3048)
			(end 0.120396 0.3048)
			(stroke
				(width 0.1)
				(type default)
			)
			(layer "F.Fab")
		)
		(fp_line
			(start 0.120396 0.3048)
			(end 0.120396 0.2794)
			(stroke
				(width 0.1)
				(type default)
			)
			(layer "F.Fab")
		)
		(fp_line
			(start -0.12065 0.3048)
			(end -0.67945 0.3048)
			(stroke
				(width 0.1)
				(type default)
			)
			(layer "F.Fab")
		)
		(fp_line
			(start -0.67945 0.3048)
			(end -0.67945 -0.305054)
			(stroke
				(width 0.1)
				(type default)
			)
			(layer "F.Fab")
		)
		(pad "1" smd circle
			(at -0.40005 0 90)
			(size 0 0)
			(layers "F.Cu" "F.Mask" "F.Paste")
			(net "P3V3_AUX")
		)
		(pad "2" smd circle
			(at 0.40005 0 90)
			(size 0 0)
			(layers "F.Cu" "F.Mask" "F.Paste")
			(net "NIC_ADC_ALERT_N")
		)
	)
	(footprint ""
		(layer "F.Cu")
		(at 477.990408 -557.9364 180)
		(property "Reference" "JPEX3_FW1"
			(at -4.0259 -1.402334 0)
			(unlocked yes)
			(layer "B.SilkS")
			(effects
				(font
					(size 0.7874 0.5842)
					(thickness 0.1524)
				)
				(justify mirror)
			)
		)
		(property "Value" ""
			(at 0 0 180)
			(layer "F.Fab")
			(effects
				(font
					(size 1.27 1.27)
				)
			)
		)
		(duplicate_pad_numbers_are_jumpers no)
		(pad "1" thru_hole circle
			(at 0 0 180)
			(size 0.4572 0.4572)
			(drill 0.2032)
			(layers "*.Cu" "*.Mask")
			(remove_unused_layers no)
			(net "Net_9087")
			(clearance 0.127)
			(thermal_gap 0.127)
			(padstack
				(mode front_inner_back)
				(layer "Inner"
					(shape circle)
					(size 0.4572 0.4572)
					(clearance 0.127)
				)
				(layer "B.Cu"
					(shape circle)
					(size 0.508 0.508)
					(clearance 0.1016)
				)
			)
		)
	)
)
